(kicad_pcb
	(version 20260206)
	(generator "pcbnew")
	(generator_version "10.0")
	(general
		(thickness 1.6)
		(legacy_teardrops no)
	)
	(paper "A4")
	(title_block
		(title "panther-plus-userver — 13130-1b_20150205.brd")
		(comment 1 "Honey Badger (Wiwynn) / footprints 1453-1456 of 1509")
	)
	(layers
		(0 "F.Cu" signal "TOP")
		(4 "In1.Cu" signal "L2")
		(6 "In2.Cu" signal "L3")
		(8 "In3.Cu" signal "L4")
		(10 "In4.Cu" signal "L5")
		(12 "In5.Cu" signal "L6")
		(14 "In6.Cu" signal "L7")
		(16 "In7.Cu" signal "L8")
		(18 "In8.Cu" signal "L9")
		(20 "In9.Cu" signal "L10")
		(22 "In10.Cu" signal "L11")
		(2 "B.Cu" signal "BOTTOM")
		(9 "F.Adhes" user "F.Adhesive")
		(11 "B.Adhes" user "B.Adhesive")
		(13 "F.Paste" user "Package Geometry/Pastemask Top")
		(15 "B.Paste" user "Package Geometry/Pastemask Bottom")
		(5 "F.SilkS" user "Ref Des/Silkscreen Top")
		(7 "B.SilkS" user "Ref Des/Silkscreen Bottom")
		(1 "F.Mask" user "Board Geometry/Soldermask Top")
		(3 "B.Mask" user "Board Geometry/Soldermask Bottom")
		(17 "Dwgs.User" user "User.Drawings")
		(19 "Cmts.User" user "User.Comments")
		(21 "Eco1.User" user "User.Eco1")
		(23 "Eco2.User" user "User.Eco2")
		(25 "Edge.Cuts" user "Board Geometry/Outline")
		(27 "Margin" user)
		(31 "F.CrtYd" user "Package Geometry/Place Bound Top")
		(29 "B.CrtYd" user "Package Geometry/Place Bound Bottom")
		(35 "F.Fab" user "Ref Des/Assembly Top")
		(33 "B.Fab" user "Ref Des/Assembly Bottom")
	)
	(footprint ""
		(layer "B.Cu")
		(at 45.7708 -22.2504)
		(property "Reference" "U28"
			(at 0 0 0)
			(layer "B.SilkS")
			(hide yes)
			(effects
				(font
					(size 1.27 1.27)
				)
				(justify mirror)
			)
		)
		(property "Value" "9DB833AGILFT-GP"
			(at 7.7724 -0.4572 0)
			(unlocked yes)
			(layer "B.Fab")
			(hide yes)
			(effects
				(font
					(size 1.016 1.016)
					(thickness 0.1524)
				)
				(justify mirror)
			)
		)
		(property "Device Type" "TSOIC48H48"
			(at 7.7724 -1.9812 0)
			(unlocked yes)
			(layer "B.Fab")
			(hide yes)
			(effects
				(font
					(size 1.016 1.016)
					(thickness 0.1524)
				)
				(justify mirror)
			)
		)
		(duplicate_pad_numbers_are_jumpers no)
		(fp_line
			(start -5.8674 -2.6162)
			(end 6.4262 -2.6162)
			(stroke
				(width 0.1524)
				(type default)
			)
			(layer "B.SilkS")
		)
		(fp_line
			(start -5.8674 2.6162)
			(end -5.8674 -2.6162)
			(stroke
				(width 0.1524)
				(type default)
			)
			(layer "B.SilkS")
		)
		(fp_line
			(start 5.7658 0)
			(end 6.4262 0.6604)
			(stroke
				(width 0.1524)
				(type default)
			)
			(layer "B.SilkS")
		)
		(fp_line
			(start 6.3754 2.6162)
			(end 6.3754 4.2926)
			(stroke
				(width 0.254)
				(type default)
			)
			(layer "B.SilkS")
		)
		(fp_line
			(start 6.4262 -2.6162)
			(end 6.4262 -0.6604)
			(stroke
				(width 0.1524)
				(type default)
			)
			(layer "B.SilkS")
		)
		(fp_line
			(start 6.4262 -0.6604)
			(end 5.7658 0)
			(stroke
				(width 0.1524)
				(type default)
			)
			(layer "B.SilkS")
		)
		(fp_line
			(start 6.4262 0.6604)
			(end 6.4262 -0.6604)
			(stroke
				(width 0.1524)
				(type default)
			)
			(layer "B.SilkS")
		)
		(fp_line
			(start 6.4262 2.6162)
			(end -5.8674 2.6162)
			(stroke
				(width 0.1524)
				(type default)
			)
			(layer "B.SilkS")
		)
		(fp_line
			(start 6.4262 2.6162)
			(end 6.4262 0.6604)
			(stroke
				(width 0.1524)
				(type default)
			)
			(layer "B.SilkS")
		)
		(fp_rect
			(start 6.5024 4.4196)
			(end -6.5024 -4.4196)
			(stroke
				(width 0)
				(type default)
			)
			(fill no)
			(layer "B.CrtYd")
		)
		(fp_rect
			(start 6.5024 4.4196)
			(end -6.5024 -4.4196)
			(stroke
				(width 0)
				(type default)
			)
			(fill no)
			(layer "B.Fab")
		)
		(pad "1" smd rect
			(at 5.75437 3.5941 180)
			(size 0.3048 1.397)
			(layers "B.Cu" "B.Mask" "B.Paste")
			(net "CLKBUFF_SRC_DIV#")
		)
		(pad "2" smd rect
			(at 5.25399 3.5941 180)
			(size 0.3048 1.397)
			(layers "B.Cu" "B.Mask" "B.Paste")
			(net "P3V3_VDDA_CLKBUFF")
		)
		(pad "3" smd rect
			(at 4.75361 3.5941 180)
			(size 0.3048 1.397)
			(layers "B.Cu" "B.Mask" "B.Paste")
			(net "GND")
		)
		(pad "4" smd rect
			(at 4.25323 3.5941 180)
			(size 0.3048 1.397)
			(layers "B.Cu" "B.Mask" "B.Paste")
			(net "CLK_100M_CLKBUFF_DP")
		)
		(pad "5" smd rect
			(at 3.75285 3.5941 180)
			(size 0.3048 1.397)
			(layers "B.Cu" "B.Mask" "B.Paste")
			(net "CLK_100M_CLKBUFF_DN")
		)
		(pad "6" smd rect
			(at 3.25247 3.5941 180)
			(size 0.3048 1.397)
			(layers "B.Cu" "B.Mask" "B.Paste")
			(net "CLKBUFF_OE0#")
		)
		(pad "7" smd rect
			(at 2.75209 3.5941 180)
			(size 0.3048 1.397)
			(layers "B.Cu" "B.Mask" "B.Paste")
			(net "CLKBUFF_OE3#")
		)
		(pad "8" smd rect
			(at 2.25171 3.5941 180)
			(size 0.3048 1.397)
			(layers "B.Cu" "B.Mask" "B.Paste")
			(net "CLK_100M_CLKBUFF_NGFF_R_DP")
		)
		(pad "9" smd rect
			(at 1.75133 3.5941 180)
			(size 0.3048 1.397)
			(layers "B.Cu" "B.Mask" "B.Paste")
			(net "CLK_100M_CLKBUFF_NGFF_R_DN")
		)
		(pad "10" smd rect
			(at 1.25095 3.5941 180)
			(size 0.3048 1.397)
			(layers "B.Cu" "B.Mask" "B.Paste")
			(net "GND")
		)
		(pad "11" smd rect
			(at 0.75057 3.5941 180)
			(size 0.3048 1.397)
			(layers "B.Cu" "B.Mask" "B.Paste")
			(net "P3V3_VDD_CLKBUFF")
		)
		(pad "12" smd rect
			(at 0.25019 3.5941 180)
			(size 0.3048 1.397)
			(layers "B.Cu" "B.Mask" "B.Paste")
			(net "CLK_100M_PCIE2_REFCLK_R_DP")
		)
		(pad "13" smd rect
			(at -0.25019 3.5941 180)
			(size 0.3048 1.397)
			(layers "B.Cu" "B.Mask" "B.Paste")
			(net "CLK_100M_PCIE2_REFCLK_R_DN")
		)
		(pad "14" smd rect
			(at -0.75057 3.5941 180)
			(size 0.3048 1.397)
			(layers "B.Cu" "B.Mask" "B.Paste")
			(net "CLKBUFF_OE1#")
		)
		(pad "15" smd rect
			(at -1.25095 3.5941 180)
			(size 0.3048 1.397)
			(layers "B.Cu" "B.Mask" "B.Paste")
			(net "CLKBUFF_OE2#")
		)
		(pad "16" smd rect
			(at -1.75133 3.5941 180)
			(size 0.3048 1.397)
			(layers "B.Cu" "B.Mask" "B.Paste")
			(net "CLK_100M_CLKBUFF_ENET_R_DP")
		)
		(pad "17" smd rect
			(at -2.25171 3.5941 180)
			(size 0.3048 1.397)
			(layers "B.Cu" "B.Mask" "B.Paste")
			(net "CLK_100M_CLKBUFF_ENET_R_DN")
		)
		(pad "18" smd rect
			(at -2.75209 3.5941 180)
			(size 0.3048 1.397)
			(layers "B.Cu" "B.Mask" "B.Paste")
			(net "GND")
		)
		(pad "19" smd rect
			(at -3.25247 3.5941 180)
			(size 0.3048 1.397)
			(layers "B.Cu" "B.Mask" "B.Paste")
			(net "P3V3_VDD_CLKBUFF")
		)
		(pad "20" smd rect
			(at -3.75285 3.5941 180)
			(size 0.3048 1.397)
			(layers "B.Cu" "B.Mask" "B.Paste")
			(net "CLK_100M_CLKBUFF_SAS_R_DP")
		)
		(pad "21" smd rect
			(at -4.25323 3.5941 180)
			(size 0.3048 1.397)
			(layers "B.Cu" "B.Mask" "B.Paste")
			(net "CLK_100M_CLKBUFF_SAS_R_DN")
		)
		(pad "22" smd rect
			(at -4.75361 3.5941 180)
			(size 0.3048 1.397)
			(layers "B.Cu" "B.Mask" "B.Paste")
			(net "CLKBUFF_BYPASS_OR_PLL")
		)
		(pad "23" smd rect
			(at -5.25399 3.5941 180)
			(size 0.3048 1.397)
			(layers "B.Cu" "B.Mask" "B.Paste")
			(net "SMB_CLKBUFF_R_CLK")
		)
		(pad "24" smd rect
			(at -5.75437 3.5941 180)
			(size 0.3048 1.397)
			(layers "B.Cu" "B.Mask" "B.Paste")
			(net "SMB_CLKBUFF_R_DATA")
		)
		(pad "25" smd rect
			(at -5.75437 -3.5941 180)
			(size 0.3048 1.397)
			(layers "B.Cu" "B.Mask" "B.Paste")
			(net "GND")
		)
		(pad "26" smd rect
			(at -5.25399 -3.5941 180)
			(size 0.3048 1.397)
			(layers "B.Cu" "B.Mask" "B.Paste")
			(net "GND")
		)
		(pad "27" smd rect
			(at -4.75361 -3.5941 180)
			(size 0.3048 1.397)
			(layers "B.Cu" "B.Mask" "B.Paste")
			(net "P3V3_VDD_CLKBUFF")
		)
		(pad "28" smd rect
			(at -4.25323 -3.5941 180)
			(size 0.3048 1.397)
			(layers "B.Cu" "B.Mask" "B.Paste")
			(net "CLKCUFF_SMB_ADDR")
		)
		(pad "29" smd rect
			(at -3.75285 -3.5941 180)
			(size 0.3048 1.397)
			(layers "B.Cu" "B.Mask" "B.Paste")
			(net "CLK_100M_CLKBUFF_PCIE_R_DN")
		)
		(pad "30" smd rect
			(at -3.25247 -3.5941 180)
			(size 0.3048 1.397)
			(layers "B.Cu" "B.Mask" "B.Paste")
			(net "CLK_100M_CLKBUFF_PCIE_R_DP")
		)
		(pad "31" smd rect
			(at -2.75209 -3.5941 180)
			(size 0.3048 1.397)
			(layers "B.Cu" "B.Mask" "B.Paste")
			(net "P3V3_VDD_CLKBUFF")
		)
		(pad "32" smd rect
			(at -2.25171 -3.5941 180)
			(size 0.3048 1.397)
			(layers "B.Cu" "B.Mask" "B.Paste")
			(net "GND")
		)
		(pad "33" smd rect
			(at -1.75133 -3.5941 180)
			(size 0.3048 1.397)
			(layers "B.Cu" "B.Mask" "B.Paste")
			(net "Net_145")
		)
		(pad "34" smd rect
			(at -1.25095 -3.5941 180)
			(size 0.3048 1.397)
			(layers "B.Cu" "B.Mask" "B.Paste")
			(net "Net_146")
		)
		(pad "35" smd rect
			(at -0.75057 -3.5941 180)
			(size 0.3048 1.397)
			(layers "B.Cu" "B.Mask" "B.Paste")
			(net "CLKBUFF_OE5#")
		)
		(pad "36" smd rect
			(at -0.25019 -3.5941 180)
			(size 0.3048 1.397)
			(layers "B.Cu" "B.Mask" "B.Paste")
			(net "CLKBUFF_OE6#")
		)
		(pad "37" smd rect
			(at 0.25019 -3.5941 180)
			(size 0.3048 1.397)
			(layers "B.Cu" "B.Mask" "B.Paste")
			(net "Net_147")
		)
		(pad "38" smd rect
			(at 0.75057 -3.5941 180)
			(size 0.3048 1.397)
			(layers "B.Cu" "B.Mask" "B.Paste")
			(net "Net_148")
		)
		(pad "39" smd rect
			(at 1.25095 -3.5941 180)
			(size 0.3048 1.397)
			(layers "B.Cu" "B.Mask" "B.Paste")
			(net "P3V3_VDD_CLKBUFF")
		)
		(pad "40" smd rect
			(at 1.75133 -3.5941 180)
			(size 0.3048 1.397)
			(layers "B.Cu" "B.Mask" "B.Paste")
			(net "CLK_GEN_PG")
		)
		(pad "41" smd rect
			(at 2.25171 -3.5941 180)
			(size 0.3048 1.397)
			(layers "B.Cu" "B.Mask" "B.Paste")
			(net "Net_149")
		)
		(pad "42" smd rect
			(at 2.75209 -3.5941 180)
			(size 0.3048 1.397)
			(layers "B.Cu" "B.Mask" "B.Paste")
			(net "Net_150")
		)
		(pad "43" smd rect
			(at 3.25247 -3.5941 180)
			(size 0.3048 1.397)
			(layers "B.Cu" "B.Mask" "B.Paste")
			(net "CLKBUFF_OE4#")
		)
		(pad "44" smd rect
			(at 3.75285 -3.5941 180)
			(size 0.3048 1.397)
			(layers "B.Cu" "B.Mask" "B.Paste")
			(net "CLKBUFF_OE7#")
		)
		(pad "45" smd rect
			(at 4.25323 -3.5941 180)
			(size 0.3048 1.397)
			(layers "B.Cu" "B.Mask" "B.Paste")
			(net "Net_151")
		)
		(pad "46" smd rect
			(at 4.75361 -3.5941 180)
			(size 0.3048 1.397)
			(layers "B.Cu" "B.Mask" "B.Paste")
			(net "CLKBUFF_IREF")
		)
		(pad "47" smd rect
			(at 5.25399 -3.5941 180)
			(size 0.3048 1.397)
			(layers "B.Cu" "B.Mask" "B.Paste")
			(net "GND")
		)
		(pad "48" smd rect
			(at 5.75437 -3.5941 180)
			(size 0.3048 1.397)
			(layers "B.Cu" "B.Mask" "B.Paste")
			(net "P3V3_VDDA_CLKBUFF")
		)
	)
	(footprint ""
		(layer "B.Cu")
		(at 153.924 -59.309)
		(property "Reference" "C105"
			(at 0 0 0)
			(layer "B.SilkS")
			(hide yes)
			(effects
				(font
					(size 1.27 1.27)
				)
				(justify mirror)
			)
		)
		(property "Value" "SC10U6D3V3MX-GP"
			(at 0.0254 -2.0193 0)
			(unlocked yes)
			(layer "B.Fab")
			(hide yes)
			(effects
				(font
					(size 1.016 1.016)
					(thickness 0.1524)
				)
				(justify mirror)
			)
		)
		(property "Device Type" "C603H38"
			(at 0.0254 -3.5433 0)
			(unlocked yes)
			(layer "B.Fab")
			(hide yes)
			(effects
				(font
					(size 1.016 1.016)
					(thickness 0.1524)
				)
				(justify mirror)
			)
		)
		(duplicate_pad_numbers_are_jumpers no)
		(fp_line
			(start 0.4064 0)
			(end -0.4064 0)
			(stroke
				(width 0.2286)
				(type default)
			)
			(layer "B.SilkS")
		)
		(fp_rect
			(start 0.635 1.1811)
			(end -0.635 -1.1811)
			(stroke
				(width 0)
				(type default)
			)
			(fill no)
			(layer "B.CrtYd")
		)
		(fp_rect
			(start 0.635 1.1811)
			(end -0.635 -1.1811)
			(stroke
				(width 0)
				(type default)
			)
			(fill no)
			(layer "B.Fab")
		)
		(pad "1" smd custom
			(at 0 -0.6604 180)
			(size 0.19685 0.19685)
			(layers "B.Cu" "B.Mask" "B.Paste")
			(net "PV_VDDR")
			(options
				(clearance outline)
				(anchor circle)
			)
			(primitives
				(gr_poly
					(pts
						(arc
							(start 0.508 0.2921)
							(mid 0.478242 0.363942)
							(end 0.4064 0.3937)
						)
						(arc
							(start -0.4064 0.3937)
							(mid -0.478242 0.363942)
							(end -0.508 0.2921)
						)
						(arc
							(start -0.508 -0.2921)
							(mid -0.478242 -0.363942)
							(end -0.4064 -0.3937)
						)
						(arc
							(start 0.4064 -0.3937)
							(mid 0.478242 -0.363942)
							(end 0.508 -0.2921)
						)
					)
					(width 0)
					(fill yes)
				)
			)
		)
		(pad "2" smd custom
			(at 0 0.6604 180)
			(size 0.19685 0.19685)
			(layers "B.Cu" "B.Mask" "B.Paste")
			(net "GND")
			(options
				(clearance outline)
				(anchor circle)
			)
			(primitives
				(gr_poly
					(pts
						(arc
							(start 0.508 0.2921)
							(mid 0.478242 0.363942)
							(end 0.4064 0.3937)
						)
						(arc
							(start -0.4064 0.3937)
							(mid -0.478242 0.363942)
							(end -0.508 0.2921)
						)
						(arc
							(start -0.508 -0.2921)
							(mid -0.478242 -0.363942)
							(end -0.4064 -0.3937)
						)
						(arc
							(start 0.4064 -0.3937)
							(mid 0.478242 -0.363942)
							(end 0.508 -0.2921)
						)
					)
					(width 0)
					(fill yes)
				)
			)
		)
	)
	(footprint ""
		(layer "B.Cu")
		(at 78.486 -22.4282 -90)
		(property "Reference" "PC195"
			(at 0 0 90)
			(layer "B.SilkS")
			(hide yes)
			(effects
				(font
					(size 1.27 1.27)
				)
				(justify mirror)
			)
		)
		(property "Value" "SCD1U16V2KX-3GP"
			(at -1.1811 -2.7051 270)
			(unlocked yes)
			(layer "B.Fab")
			(hide yes)
			(effects
				(font
					(size 1.016 1.016)
					(thickness 0.1524)
				)
				(justify mirror)
			)
		)
		(property "Device Type" "C402H22"
			(at -1.1811 -4.2291 270)
			(unlocked yes)
			(layer "B.Fab")
			(hide yes)
			(effects
				(font
					(size 1.016 1.016)
					(thickness 0.1524)
				)
				(justify mirror)
			)
		)
		(duplicate_pad_numbers_are_jumpers no)
		(fp_rect
			(start 0.381 0.7366)
			(end -0.381 -0.7366)
			(stroke
				(width 0)
				(type default)
			)
			(fill no)
			(layer "B.CrtYd")
		)
		(fp_rect
			(start 0.381 0.7366)
			(end -0.381 -0.7366)
			(stroke
				(width 0)
				(type default)
			)
			(fill no)
			(layer "B.Fab")
		)
		(pad "1" smd custom
			(at 0 -0.4572 90)
			(size 0.1143 0.1143)
			(layers "B.Cu" "B.Mask" "B.Paste")
			(net "TPS74801_1V35_BIAS")
			(options
				(clearance outline)
				(anchor circle)
			)
			(primitives
				(gr_poly
					(pts
						(arc
							(start -0.254 0.1778)
							(mid -0.239121 0.213721)
							(end -0.2032 0.2286)
						)
						(arc
							(start 0.2032 0.2286)
							(mid 0.239121 0.213721)
							(end 0.254 0.1778)
						)
						(arc
							(start 0.254 -0.1778)
							(mid 0.239121 -0.213721)
							(end 0.2032 -0.2286)
						)
						(arc
							(start -0.2032 -0.2286)
							(mid -0.239121 -0.213721)
							(end -0.254 -0.1778)
						)
					)
					(width 0)
					(fill yes)
				)
			)
		)
		(pad "2" smd custom
			(at 0 0.4572 90)
			(size 0.1143 0.1143)
			(layers "B.Cu" "B.Mask" "B.Paste")
			(net "GND")
			(options
				(clearance outline)
				(anchor circle)
			)
			(primitives
				(gr_poly
					(pts
						(arc
							(start -0.254 0.1778)
							(mid -0.239121 0.213721)
							(end -0.2032 0.2286)
						)
						(arc
							(start 0.2032 0.2286)
							(mid 0.239121 0.213721)
							(end 0.254 0.1778)
						)
						(arc
							(start 0.254 -0.1778)
							(mid 0.239121 -0.213721)
							(end 0.2032 -0.2286)
						)
						(arc
							(start -0.2032 -0.2286)
							(mid -0.239121 -0.213721)
							(end -0.254 -0.1778)
						)
					)
					(width 0)
					(fill yes)
				)
			)
		)
	)
	(footprint ""
		(layer "B.Cu")
		(at 134.366 -44.704 -90)
		(property "Reference" "C149"
			(at 0 0 90)
			(layer "B.SilkS")
			(hide yes)
			(effects
				(font
					(size 1.27 1.27)
				)
				(justify mirror)
			)
		)
		(property "Value" "SCD1U10V2KX-5GP"
			(at -1.1811 -2.7051 270)
			(unlocked yes)
			(layer "B.Fab")
			(hide yes)
			(effects
				(font
					(size 1.016 1.016)
					(thickness 0.1524)
				)
				(justify mirror)
			)
		)
		(property "Device Type" "C402H22"
			(at -1.1811 -4.2291 270)
			(unlocked yes)
			(layer "B.Fab")
			(hide yes)
			(effects
				(font
					(size 1.016 1.016)
					(thickness 0.1524)
				)
				(justify mirror)
			)
		)
		(duplicate_pad_numbers_are_jumpers no)
		(fp_rect
			(start 0.381 0.7366)
			(end -0.381 -0.7366)
			(stroke
				(width 0)
				(type default)
			)
			(fill no)
			(layer "B.CrtYd")
		)
		(fp_rect
			(start 0.381 0.7366)
			(end -0.381 -0.7366)
			(stroke
				(width 0)
				(type default)
			)
			(fill no)
			(layer "B.Fab")
		)
		(pad "1" smd custom
			(at 0 -0.4572 90)
			(size 0.1143 0.1143)
			(layers "B.Cu" "B.Mask" "B.Paste")
			(net "P2V5_STBY")
			(options
				(clearance outline)
				(anchor circle)
			)
			(primitives
				(gr_poly
					(pts
						(arc
							(start -0.254 0.1778)
							(mid -0.239121 0.213721)
							(end -0.2032 0.2286)
						)
						(arc
							(start 0.2032 0.2286)
							(mid 0.239121 0.213721)
							(end 0.254 0.1778)
						)
						(arc
							(start 0.254 -0.1778)
							(mid 0.239121 -0.213721)
							(end 0.2032 -0.2286)
						)
						(arc
							(start -0.2032 -0.2286)
							(mid -0.239121 -0.213721)
							(end -0.254 -0.1778)
						)
					)
					(width 0)
					(fill yes)
				)
			)
		)
		(pad "2" smd custom
			(at 0 0.4572 90)
			(size 0.1143 0.1143)
			(layers "B.Cu" "B.Mask" "B.Paste")
			(net "GND")
			(options
				(clearance outline)
				(anchor circle)
			)
			(primitives
				(gr_poly
					(pts
						(arc
							(start -0.254 0.1778)
							(mid -0.239121 0.213721)
							(end -0.2032 0.2286)
						)
						(arc
							(start 0.2032 0.2286)
							(mid 0.239121 0.213721)
							(end 0.254 0.1778)
						)
						(arc
							(start 0.254 -0.1778)
							(mid 0.239121 -0.213721)
							(end 0.2032 -0.2286)
						)
						(arc
							(start -0.2032 -0.2286)
							(mid -0.239121 -0.213721)
							(end -0.254 -0.1778)
						)
					)
					(width 0)
					(fill yes)
				)
			)
		)
	)
)
